# T6G (Grand Teton) — schematic netlist excerpt (pin names and nets, part order shuffled) for the footprints in the layout excerpt that follows; sources: Cadence DE-HDL packaged netlist, KiCad conversion of 04192023_DAF0TMB3IC0_F0TG_MB_C_brd_V02_OCP.brd

L25  Q_INDUCTOR  BLM18PG300SN1D IND  pkg SMLF  page 258 : \1\ = P3V3_AUX ; \2\ = P3V3_ADC128_2_VCC
C1014  Q_CAP  0.1UF 10V 10% X7S  pkg C0201  page 312 : A = P0V9_CPU0_RT3_2A_2D ; B = GND

(kicad_pcb
	(version 20260206)
	(generator "pcbnew")
	(generator_version "10.0")
	(general
		(thickness 1.6)
		(legacy_teardrops no)
	)
	(paper "A4")
	(title_block
		(title "04192023_DAF0TMB3IC0_F0TG_MB_C_brd_V02_OCP.brd")
		(comment 1 "Grand Teton / footprints 7352-7353 of 8354")
	)
	(layers
		(0 "F.Cu" signal "TOP")
		(4 "In1.Cu" signal "GND")
		(6 "In2.Cu" signal "IN1")
		(8 "In3.Cu" signal "GND1")
		(10 "In4.Cu" signal "IN2")
		(12 "In5.Cu" signal "GND2")
		(14 "In6.Cu" signal "IN3")
		(16 "In7.Cu" signal "GND3")
		(18 "In8.Cu" signal "VCC")
		(20 "In9.Cu" signal "VCC1")
		(22 "In10.Cu" signal "GND4")
		(24 "In11.Cu" signal "IN4")
		(26 "In12.Cu" signal "GND5")
		(28 "In13.Cu" signal "IN5")
		(30 "In14.Cu" signal "GND6")
		(32 "In15.Cu" signal "IN6")
		(34 "In16.Cu" signal "GND7")
		(2 "B.Cu" signal "BOTTOM")
		(9 "F.Adhes" user "F.Adhesive")
		(11 "B.Adhes" user "B.Adhesive")
		(13 "F.Paste" user "Package Geometry/Pastemask Top")
		(15 "B.Paste" user "Package Geometry/Pastemask Bottom")
		(5 "F.SilkS" user "Ref Des/Silkscreen Top")
		(7 "B.SilkS" user "Ref Des/Silkscreen Bottom")
		(1 "F.Mask" user "Board Geometry/Soldermask Top")
		(3 "B.Mask" user "Board Geometry/Soldermask Bottom")
		(17 "Dwgs.User" user "User.Drawings")
		(19 "Cmts.User" user "User.Comments")
		(21 "Eco1.User" user "User.Eco1")
		(23 "Eco2.User" user "User.Eco2")
		(25 "Edge.Cuts" user "Board Geometry/Outline")
		(27 "Margin" user)
		(31 "F.CrtYd" user "Package Geometry/Place Bound Top")
		(29 "B.CrtYd" user "Package Geometry/Place Bound Bottom")
		(35 "F.Fab" user "Ref Des/Assembly Top")
		(33 "B.Fab" user "Ref Des/Assembly Bottom")
	)
	(footprint ""
		(layer "B.Cu")
		(at 213.02091 -324.262242 180)
		(property "Reference" "L25"
			(at 0 0 0)
			(layer "B.SilkS")
			(hide yes)
			(effects
				(font
					(size 1.27 1.27)
				)
				(justify mirror)
			)
		)
		(property "Value" ""
			(at 0 0 0)
			(layer "B.Fab")
			(effects
				(font
					(size 1.27 1.27)
				)
				(justify mirror)
			)
		)
		(duplicate_pad_numbers_are_jumpers no)
		(fp_line
			(start 1.27 0.5842)
			(end 1.27 -0.5842)
			(stroke
				(width 0.1524)
				(type default)
			)
			(layer "B.SilkS")
		)
		(fp_line
			(start 1.27 -0.5588)
			(end 1.27 -0.5842)
			(stroke
				(width 0.1524)
				(type default)
			)
			(layer "B.SilkS")
		)
		(fp_line
			(start 1.27 -0.5842)
			(end -1.27 -0.5842)
			(stroke
				(width 0.1524)
				(type default)
			)
			(layer "B.SilkS")
		)
		(fp_line
			(start -1.27 0.5842)
			(end 1.27 0.5842)
			(stroke
				(width 0.1524)
				(type default)
			)
			(layer "B.SilkS")
		)
		(fp_line
			(start -1.27 0.5842)
			(end -1.27 -0.5842)
			(stroke
				(width 0.1524)
				(type default)
			)
			(layer "B.SilkS")
		)
		(fp_line
			(start 1.194308 0.406654)
			(end 1.194308 -0.406654)
			(stroke
				(width 0.1)
				(type default)
			)
			(layer "B.Fab")
		)
		(fp_line
			(start 1.194308 -0.406654)
			(end 0.9144 -0.406654)
			(stroke
				(width 0.1)
				(type default)
			)
			(layer "B.Fab")
		)
		(fp_line
			(start 0.9144 0.508)
			(end 0.9144 0.406654)
			(stroke
				(width 0.1)
				(type default)
			)
			(layer "B.Fab")
		)
		(fp_line
			(start 0.9144 0.406654)
			(end 1.194308 0.406654)
			(stroke
				(width 0.1)
				(type default)
			)
			(layer "B.Fab")
		)
		(fp_line
			(start 0.9144 -0.406654)
			(end 0.9144 -0.508)
			(stroke
				(width 0.1)
				(type default)
			)
			(layer "B.Fab")
		)
		(fp_line
			(start 0.9144 -0.508)
			(end -0.9144 -0.508)
			(stroke
				(width 0.1)
				(type default)
			)
			(layer "B.Fab")
		)
		(fp_line
			(start -0.9144 0.508)
			(end 0.9144 0.508)
			(stroke
				(width 0.1)
				(type default)
			)
			(layer "B.Fab")
		)
		(fp_line
			(start -0.9144 0.4064)
			(end -0.9144 0.508)
			(stroke
				(width 0.1)
				(type default)
			)
			(layer "B.Fab")
		)
		(fp_line
			(start -0.9144 -0.406654)
			(end -1.1938 -0.406654)
			(stroke
				(width 0.1)
				(type default)
			)
			(layer "B.Fab")
		)
		(fp_line
			(start -0.9144 -0.508)
			(end -0.9144 -0.406654)
			(stroke
				(width 0.1)
				(type default)
			)
			(layer "B.Fab")
		)
		(fp_line
			(start -1.1938 0.4064)
			(end -0.9144 0.4064)
			(stroke
				(width 0.1)
				(type default)
			)
			(layer "B.Fab")
		)
		(fp_line
			(start -1.1938 -0.406654)
			(end -1.1938 0.4064)
			(stroke
				(width 0.1)
				(type default)
			)
			(layer "B.Fab")
		)
		(pad "1" smd rect
			(at 0.7366 0 90)
			(size 0.7112 0.8128)
			(layers "B.Cu" "B.Mask" "B.Paste")
			(net "P3V3_AUX")
		)
		(pad "2" smd rect
			(at -0.7366 0 90)
			(size 0.7112 0.8128)
			(layers "B.Cu" "B.Mask" "B.Paste")
			(net "P3V3_ADC128_2_VCC")
		)
	)
	(footprint ""
		(layer "B.Cu")
		(at 383.818384 -396.393162 -90)
		(property "Reference" "C1014"
			(at 0 0 90)
			(layer "B.SilkS")
			(hide yes)
			(effects
				(font
					(size 1.27 1.27)
				)
				(justify mirror)
			)
		)
		(property "Value" ""
			(at 0 0 90)
			(layer "B.Fab")
			(effects
				(font
					(size 1.27 1.27)
				)
				(justify mirror)
			)
		)
		(duplicate_pad_numbers_are_jumpers no)
		(fp_line
			(start -0.299974 0.150114)
			(end 0.299974 0.150114)
			(stroke
				(width 0.1)
				(type default)
			)
			(layer "B.Fab")
		)
		(fp_line
			(start 0.299974 0.150114)
			(end 0.299974 -0.150114)
			(stroke
				(width 0.1)
				(type default)
			)
			(layer "B.Fab")
		)
		(fp_line
			(start -0.299974 -0.150114)
			(end -0.299974 0.150114)
			(stroke
				(width 0.1)
				(type default)
			)
			(layer "B.Fab")
		)
		(fp_line
			(start 0.299974 -0.150114)
			(end -0.299974 -0.150114)
			(stroke
				(width 0.1)
				(type default)
			)
			(layer "B.Fab")
		)
		(pad "1" smd rect
			(at 0.2667 0 90)
			(size 0.3048 0.381)
			(layers "B.Cu" "B.Mask" "B.Paste")
			(net "P0V9_CPU0_RT3_2A_2D")
		)
		(pad "2" smd rect
			(at -0.2667 0 90)
			(size 0.3048 0.381)
			(layers "B.Cu" "B.Mask" "B.Paste")
			(net "GND")
		)
	)
)
